(kicad_pcb
	(version 20260206)
	(generator "pcbnew")
	(generator_version "10.0")
	(general
		(thickness 1.6)
		(legacy_teardrops no)
	)
	(paper "A4")
	(title_block
		(title "Bryce Canyon_F.DPB_16315-1-OCP.brd")
		(comment 1 "Bryce Canyon / footprints 1669-1672 of 2223")
	)
	(layers
		(0 "F.Cu" signal "TOP")
		(4 "In1.Cu" signal "L2GND")
		(6 "In2.Cu" signal "L3")
		(8 "In3.Cu" signal "L4GND")
		(10 "In4.Cu" signal "L5")
		(12 "In5.Cu" signal "L6VCC")
		(14 "In6.Cu" signal "L7VCC")
		(16 "In7.Cu" signal "L8")
		(18 "In8.Cu" signal "L9GND")
		(20 "In9.Cu" signal "L10")
		(22 "In10.Cu" signal "L11GND")
		(2 "B.Cu" signal "BOTTOM")
		(9 "F.Adhes" user "F.Adhesive")
		(11 "B.Adhes" user "B.Adhesive")
		(13 "F.Paste" user "Package Geometry/Pastemask Top")
		(15 "B.Paste" user "Package Geometry/Pastemask Bottom")
		(5 "F.SilkS" user "Ref Des/Silkscreen Top")
		(7 "B.SilkS" user "Ref Des/Silkscreen Bottom")
		(1 "F.Mask" user "Board Geometry/Soldermask Top")
		(3 "B.Mask" user "Board Geometry/Soldermask Bottom")
		(17 "Dwgs.User" user "User.Drawings")
		(19 "Cmts.User" user "User.Comments")
		(21 "Eco1.User" user "User.Eco1")
		(23 "Eco2.User" user "User.Eco2")
		(25 "Edge.Cuts" user "Board Geometry/Outline")
		(27 "Margin" user)
		(31 "F.CrtYd" user "Package Geometry/Place Bound Top")
		(29 "B.CrtYd" user "Package Geometry/Place Bound Bottom")
		(35 "F.Fab" user "Ref Des/Assembly Top")
		(33 "B.Fab" user "Ref Des/Assembly Bottom")
	)
	(footprint ""
		(layer "F.Cu")
		(at 460.5909 -282.872942 -90)
		(property "Reference" "Q60"
			(at 0 0 270)
			(layer "F.SilkS")
			(hide yes)
			(effects
				(font
					(size 1.27 1.27)
				)
			)
		)
		(property "Value" "AO4406AL-GP"
			(at -3.707384 -1.5367 270)
			(unlocked yes)
			(layer "F.Fab")
			(hide yes)
			(effects
				(font
					(size 1.016 1.016)
					(thickness 0.1524)
				)
			)
		)
		(property "Device Type" "SOIC8H69"
			(at -3.707384 -3.0607 270)
			(unlocked yes)
			(layer "F.Fab")
			(hide yes)
			(effects
				(font
					(size 1.016 1.016)
					(thickness 0.1524)
				)
			)
		)
		(duplicate_pad_numbers_are_jumpers no)
		(fp_line
			(start -2.6289 3.4417)
			(end -2.6289 1.4732)
			(stroke
				(width 0.381)
				(type default)
			)
			(layer "F.SilkS")
		)
		(fp_line
			(start -2.7432 1.4224)
			(end -2.6416 1.4224)
			(stroke
				(width 0.1524)
				(type default)
			)
			(layer "F.SilkS")
		)
		(fp_line
			(start -2.7432 1.4224)
			(end 2.1336 1.4224)
			(stroke
				(width 0.1524)
				(type default)
			)
			(layer "F.SilkS")
		)
		(fp_line
			(start 2.1336 1.4224)
			(end 2.1336 -1.4224)
			(stroke
				(width 0.1524)
				(type default)
			)
			(layer "F.SilkS")
		)
		(fp_line
			(start -2.1844 -0.0508)
			(end -2.7178 0.508)
			(stroke
				(width 0.1524)
				(type default)
			)
			(layer "F.SilkS")
		)
		(fp_line
			(start -2.7178 -0.508)
			(end -2.1844 -0.0508)
			(stroke
				(width 0.1524)
				(type default)
			)
			(layer "F.SilkS")
		)
		(fp_line
			(start -2.7432 -1.4224)
			(end -2.7432 1.4224)
			(stroke
				(width 0.1524)
				(type default)
			)
			(layer "F.SilkS")
		)
		(fp_line
			(start 2.1336 -1.4224)
			(end -2.7432 -1.4224)
			(stroke
				(width 0.1524)
				(type default)
			)
			(layer "F.SilkS")
		)
		(fp_poly
			(pts
				(xy -2.2098 -1.4224) (xy -2.2098 1.4224) (xy 2.2098 1.4224) (xy 2.2098 -1.4224)
			)
			(stroke
				(width 0)
				(type default)
			)
			(fill yes)
			(layer "F.SilkS")
		)
		(fp_rect
			(start -2.450084 2.999994)
			(end 2.450084 -2.999994)
			(stroke
				(width 0)
				(type default)
			)
			(fill no)
			(layer "F.CrtYd")
		)
		(fp_poly
			(pts
				(xy -2.8194 3.6322) (xy -2.8194 -3.6322) (xy 2.8194 -3.6322) (xy 2.8194 1.18364) (xy 2.450084 1.18364)
				(xy 2.450084 -2.999994) (xy -2.450084 -2.999994) (xy -2.450084 2.999994) (xy 2.450084 2.999994)
				(xy 2.450084 1.18618) (xy 2.8194 1.18618) (xy 2.8194 3.6322)
			)
			(stroke
				(width 0)
				(type default)
			)
			(fill no)
			(layer "F.CrtYd")
		)
		(fp_rect
			(start -2.8194 3.6322)
			(end 2.8194 -3.6322)
			(stroke
				(width 0)
				(type default)
			)
			(fill no)
			(layer "F.Fab")
		)
		(pad "1" smd rect
			(at -1.905 2.54 270)
			(size 0.635 1.651)
			(layers "F.Cu" "F.Mask" "F.Paste")
			(net "P5V_HDD10")
		)
		(pad "2" smd rect
			(at -0.635 2.54 270)
			(size 0.635 1.651)
			(layers "F.Cu" "F.Mask" "F.Paste")
			(net "P5V_HDD10")
		)
		(pad "3" smd rect
			(at 0.635 2.54 270)
			(size 0.635 1.651)
			(layers "F.Cu" "F.Mask" "F.Paste")
			(net "P5V_HDD10")
		)
		(pad "4" smd rect
			(at 1.905 2.54 270)
			(size 0.635 1.651)
			(layers "F.Cu" "F.Mask" "F.Paste")
			(net "SW_HDD_P10")
		)
		(pad "5" smd rect
			(at 1.905 -2.54 270)
			(size 0.635 1.651)
			(layers "F.Cu" "F.Mask" "F.Paste")
			(net "P5V_A_3")
		)
		(pad "6" smd rect
			(at 0.635 -2.54 270)
			(size 0.635 1.651)
			(layers "F.Cu" "F.Mask" "F.Paste")
			(net "P5V_A_3")
		)
		(pad "7" smd rect
			(at -0.635 -2.54 270)
			(size 0.635 1.651)
			(layers "F.Cu" "F.Mask" "F.Paste")
			(net "P5V_A_3")
		)
		(pad "8" smd rect
			(at -1.905 -2.54 270)
			(size 0.635 1.651)
			(layers "F.Cu" "F.Mask" "F.Paste")
			(net "P5V_A_3")
		)
	)
	(footprint ""
		(layer "F.Cu")
		(at 349.758 -295.0718 -90)
		(property "Reference" "R295"
			(at 0 0 270)
			(layer "F.SilkS")
			(hide yes)
			(effects
				(font
					(size 1.27 1.27)
				)
			)
		)
		(property "Value" "220R3F-1-GP"
			(at -0.0254 -2.5146 270)
			(unlocked yes)
			(layer "F.Fab")
			(hide yes)
			(effects
				(font
					(size 1.016 1.016)
					(thickness 0.1524)
				)
			)
		)
		(property "Device Type" "R603H22"
			(at -0.0254 -4.0386 270)
			(unlocked yes)
			(layer "F.Fab")
			(hide yes)
			(effects
				(font
					(size 1.016 1.016)
					(thickness 0.1524)
				)
			)
		)
		(duplicate_pad_numbers_are_jumpers no)
		(fp_line
			(start -0.4826 0)
			(end -0.2032 0)
			(stroke
				(width 0.2032)
				(type default)
			)
			(layer "F.SilkS")
		)
		(fp_line
			(start 0.2032 0)
			(end 0.4826 0)
			(stroke
				(width 0.2032)
				(type default)
			)
			(layer "F.SilkS")
		)
		(fp_rect
			(start -0.5842 1.3335)
			(end 0.5842 -1.3335)
			(stroke
				(width 0)
				(type default)
			)
			(fill no)
			(layer "F.CrtYd")
		)
		(fp_rect
			(start -0.5842 1.3335)
			(end 0.5842 -1.3335)
			(stroke
				(width 0)
				(type default)
			)
			(fill no)
			(layer "F.Fab")
		)
		(pad "1" smd custom
			(at 0 -0.762 270)
			(size 0.2159 0.2159)
			(layers "F.Cu" "F.Mask" "F.Paste")
			(net "HDD_PRSNT_7")
			(options
				(clearance outline)
				(anchor circle)
			)
			(primitives
				(gr_poly
					(pts
						(arc
							(start -0.3302 -0.4318)
							(mid -0.402042 -0.402042)
							(end -0.4318 -0.3302)
						)
						(arc
							(start -0.4318 0.3302)
							(mid -0.402042 0.402042)
							(end -0.3302 0.4318)
						)
						(arc
							(start 0.3302 0.4318)
							(mid 0.402042 0.402042)
							(end 0.4318 0.3302)
						)
						(arc
							(start 0.4318 -0.3302)
							(mid 0.402042 -0.402042)
							(end 0.3302 -0.4318)
						)
					)
					(width 0)
					(fill yes)
				)
			)
		)
		(pad "2" smd custom
			(at 0 0.762 270)
			(size 0.2159 0.2159)
			(layers "F.Cu" "F.Mask" "F.Paste")
			(net "DRIVE_A_7_INS")
			(options
				(clearance outline)
				(anchor circle)
			)
			(primitives
				(gr_poly
					(pts
						(arc
							(start -0.3302 -0.4318)
							(mid -0.402042 -0.402042)
							(end -0.4318 -0.3302)
						)
						(arc
							(start -0.4318 0.3302)
							(mid -0.402042 0.402042)
							(end -0.3302 0.4318)
						)
						(arc
							(start 0.3302 0.4318)
							(mid 0.402042 0.402042)
							(end 0.4318 0.3302)
						)
						(arc
							(start 0.4318 -0.3302)
							(mid 0.402042 -0.402042)
							(end 0.3302 -0.4318)
						)
					)
					(width 0)
					(fill yes)
				)
			)
		)
	)
	(footprint ""
		(layer "F.Cu")
		(at 286.100012 -406.699974 -90)
		(property "Reference" "PWR1"
			(at 0 0 270)
			(layer "F.SilkS")
			(hide yes)
			(effects
				(font
					(size 1.27 1.27)
				)
			)
		)
		(property "Value" "AMP-CONN8-2R-2-GP"
			(at 15.875 6.604 270)
			(unlocked yes)
			(layer "F.Fab")
			(hide yes)
			(effects
				(font
					(size 1.016 1.016)
					(thickness 0.1524)
				)
			)
		)
		(property "Device Type" "PREFIT-8P-5697-1H404"
			(at 15.875 5.08 270)
			(unlocked yes)
			(layer "F.Fab")
			(hide yes)
			(effects
				(font
					(size 1.016 1.016)
					(thickness 0.1524)
				)
			)
		)
		(duplicate_pad_numbers_are_jumpers no)
		(fp_line
			(start -1.4478 8.2804)
			(end -1.4478 -1.9558)
			(stroke
				(width 0.1524)
				(type default)
			)
			(layer "F.SilkS")
		)
		(fp_line
			(start 4.6482 8.2804)
			(end -1.4478 8.2804)
			(stroke
				(width 0.1524)
				(type default)
			)
			(layer "F.SilkS")
		)
		(fp_line
			(start -1.4478 -1.9558)
			(end 4.6482 -1.9558)
			(stroke
				(width 0.1524)
				(type default)
			)
			(layer "F.SilkS")
		)
		(fp_line
			(start 4.6482 -1.9558)
			(end 4.6482 8.2804)
			(stroke
				(width 0.1524)
				(type default)
			)
			(layer "F.SilkS")
		)
		(fp_poly
			(pts
				(xy -1.4478 8.2804) (xy -1.4478 -0.864616) (xy -0.8636 -0.864616) (xy -0.8636 8.128) (xy 4.063492 8.128)
				(xy 4.063492 -0.864616) (xy 4.6482 -0.864616) (xy 4.6482 8.2804)
			)
			(stroke
				(width 0)
				(type default)
			)
			(fill yes)
			(layer "F.SilkS")
		)
		(fp_poly
			(pts
				(arc
					(start 0.2032 7.8486)
					(mid 0 8.0518)
					(end -0.2032 7.8486)
				)
				(arc
					(start -0.2032 7.6454)
					(mid 0 7.4422)
					(end 0.2032 7.6454)
				)
			)
			(stroke
				(width 0)
				(type default)
			)
			(fill yes)
			(layer "F.SilkS")
		)
		(fp_poly
			(pts
				(arc
					(start 3.403092 7.8486)
					(mid 3.199892 8.0518)
					(end 2.996692 7.8486)
				)
				(arc
					(start 2.996692 7.6454)
					(mid 3.199892 7.4422)
					(end 3.403092 7.6454)
				)
			)
			(stroke
				(width 0)
				(type default)
			)
			(fill yes)
			(layer "F.SilkS")
		)
		(fp_rect
			(start -5.6134 11.938)
			(end 8.8138 -5.6134)
			(stroke
				(width 0)
				(type default)
			)
			(fill no)
			(layer "B.CrtYd")
		)
		(fp_rect
			(start -1.1938 8.0264)
			(end 4.3942 -1.7018)
			(stroke
				(width 0)
				(type default)
			)
			(fill no)
			(layer "F.CrtYd")
		)
		(fp_poly
			(pts
				(xy -6.1976 13.0302) (xy -6.1976 -6.7056) (xy 9.398 -6.7056) (xy 9.398 0) (xy 4.9022 0) (xy 4.9022 -2.2098)
				(xy -1.7018 -2.2098) (xy -1.7018 8.5344) (xy 4.9022 8.5344) (xy 4.9022 0.0127) (xy 9.398 0.0127)
				(xy 9.398 13.0302)
			)
			(stroke
				(width 0)
				(type default)
			)
			(fill no)
			(layer "F.CrtYd")
		)
		(fp_poly
			(pts
				(xy -1.7018 8.5344) (xy -1.7018 -2.2098) (xy 4.9022 -2.2098) (xy 4.9022 0) (xy 4.3942 0) (xy 4.3942 -1.7018)
				(xy -1.1938 -1.7018) (xy -1.1938 8.0264) (xy 4.3942 8.0264) (xy 4.3942 0.0127) (xy 4.9022 0.0127)
				(xy 4.9022 8.5344)
			)
			(stroke
				(width 0)
				(type default)
			)
			(fill no)
			(layer "F.CrtYd")
		)
		(fp_rect
			(start -10.6172 16.9418)
			(end 13.8176 -10.6172)
			(stroke
				(width 0)
				(type default)
			)
			(fill no)
			(layer "B.Fab")
		)
		(fp_rect
			(start -5.6134 11.938)
			(end 8.8138 -5.6134)
			(stroke
				(width 0)
				(type default)
			)
			(fill no)
			(layer "B.Fab")
		)
		(fp_rect
			(start -11.2014 18.034)
			(end 14.4018 -11.7094)
			(stroke
				(width 0)
				(type default)
			)
			(fill no)
			(layer "F.Fab")
		)
		(fp_rect
			(start -6.1976 13.0302)
			(end 9.398 -6.7056)
			(stroke
				(width 0)
				(type default)
			)
			(fill no)
			(layer "F.Fab")
		)
		(fp_rect
			(start -1.7018 8.5344)
			(end 4.9022 -2.2098)
			(stroke
				(width 0)
				(type default)
			)
			(fill no)
			(layer "F.Fab")
		)
		(fp_text user "Pre Fit"
			(at -1.778 -1.3462 270)
			(unlocked yes)
			(layer "F.SilkS")
			(effects
				(font
					(size 1.016 1.016)
					(thickness 0.1524)
				)
				(justify left)
			)
		)
		(fp_text user "Can not place BGA,CSP,Wave Solder Component"
			(at -24.9428 14.9352 270)
			(unlocked yes)
			(layer "B.Fab")
			(effects
				(font
					(size 1.016 1.016)
					(thickness 0.1524)
				)
				(justify left)
			)
		)
		(fp_text user "Can not place BGA,CSP,Wave Solder Component"
			(at -22.987 15.9258 270)
			(unlocked yes)
			(layer "F.Fab")
			(effects
				(font
					(size 1.016 1.016)
					(thickness 0.1524)
				)
				(justify left)
			)
		)
		(fp_text user "High Limit 2mm"
			(at -6.604 11.3538 270)
			(unlocked yes)
			(layer "F.Fab")
			(effects
				(font
					(size 1.016 1.016)
					(thickness 0.1524)
				)
				(justify left)
			)
		)
		(pad "A1" thru_hole oval
			(at 0 0 270)
			(size 1.2192 2.921)
			(drill 0.739902
				(offset 0 0.849884)
			)
			(layers "*.Cu" "*.Mask")
			(remove_unused_layers no)
			(net "P12V_A")
			(clearance 0.127)
			(thermal_gap 0.127)
			(padstack
				(mode front_inner_back)
				(layer "Inner"
					(shape circle)
					(size 1.2192 1.2192)
					(clearance 0.127)
				)
				(layer "B.Cu"
					(shape circle)
					(size 1.2192 1.2192)
					(clearance 0.127)
				)
			)
		)
		(pad "A2" thru_hole circle
			(at 0 1.700022 270)
			(size 1.2192 1.2192)
			(drill 0.739902)
			(layers "*.Cu" "*.Mask")
			(remove_unused_layers no)
			(net "P12V_A")
			(clearance 0.127)
			(thermal_gap 0.127)
		)
		(pad "A3" thru_hole oval
			(at 0 4.629912 270)
			(size 1.2192 2.921)
			(drill 0.739902
				(offset 0 0.849884)
			)
			(layers "*.Cu" "*.Mask")
			(remove_unused_layers no)
			(net "P12V_A")
			(clearance 0.127)
			(thermal_gap 0.127)
			(padstack
				(mode front_inner_back)
				(layer "Inner"
					(shape circle)
					(size 1.2192 1.2192)
					(clearance 0.127)
				)
				(layer "B.Cu"
					(shape circle)
					(size 1.2192 1.2192)
					(clearance 0.127)
				)
			)
		)
		(pad "A4" thru_hole circle
			(at 0 6.329934 270)
			(size 1.2192 1.2192)
			(drill 0.739902)
			(layers "*.Cu" "*.Mask")
			(remove_unused_layers no)
			(net "P12V_A")
			(clearance 0.127)
			(thermal_gap 0.127)
		)
		(pad "B1" thru_hole oval
			(at 3.199892 0 270)
			(size 1.2192 2.921)
			(drill 0.739902
				(offset 0 0.849884)
			)
			(layers "*.Cu" "*.Mask")
			(remove_unused_layers no)
			(net "GND")
			(clearance 0.127)
			(thermal_gap 0.127)
			(padstack
				(mode front_inner_back)
				(layer "Inner"
					(shape circle)
					(size 1.2192 1.2192)
					(clearance 0.127)
				)
				(layer "B.Cu"
					(shape circle)
					(size 1.2192 1.2192)
					(clearance 0.127)
				)
			)
		)
		(pad "B2" thru_hole circle
			(at 3.199892 1.700022 270)
			(size 1.2192 1.2192)
			(drill 0.739902)
			(layers "*.Cu" "*.Mask")
			(remove_unused_layers no)
			(net "GND")
			(clearance 0.127)
			(thermal_gap 0.127)
		)
		(pad "B3" thru_hole oval
			(at 3.199892 4.629912 270)
			(size 1.2192 2.921)
			(drill 0.739902
				(offset 0 0.849884)
			)
			(layers "*.Cu" "*.Mask")
			(remove_unused_layers no)
			(net "GND")
			(clearance 0.127)
			(thermal_gap 0.127)
			(padstack
				(mode front_inner_back)
				(layer "Inner"
					(shape circle)
					(size 1.2192 1.2192)
					(clearance 0.127)
				)
				(layer "B.Cu"
					(shape circle)
					(size 1.2192 1.2192)
					(clearance 0.127)
				)
			)
		)
		(pad "B4" thru_hole circle
			(at 3.199892 6.329934 270)
			(size 1.2192 1.2192)
			(drill 0.739902)
			(layers "*.Cu" "*.Mask")
			(remove_unused_layers no)
			(net "GND")
			(clearance 0.127)
			(thermal_gap 0.127)
		)
		(zone
			(layer "F.Cu")
			(hatch none 0.5)
			(connect_pads
				(clearance 0)
			)
			(min_thickness 0.25)
			(keepout
				(tracks allowed)
				(vias not_allowed)
				(pads allowed)
				(copperpour not_allowed)
				(footprints allowed)
			)
			(placement
				(enabled no)
				(sheetname "")
			)
			(fill
				(thermal_gap 0.5)
				(thermal_bridge_width 0.5)
				(island_removal_mode 0)
			)
			(polygon
				(pts
					(xy 278.91994 -407.549858) (xy 278.91994 -402.649944) (xy 286.949896 -402.649944) (xy 286.949896 -407.549858)
				)
			)
		)
		(zone
			(layer "F.Cu")
			(hatch none 0.5)
			(connect_pads
				(clearance 0)
			)
			(min_thickness 0.25)
			(keepout
				(tracks not_allowed)
				(vias allowed)
				(pads allowed)
				(copperpour not_allowed)
				(footprints allowed)
			)
			(placement
				(enabled no)
				(sheetname "")
			)
			(fill
				(thermal_gap 0.5)
				(thermal_bridge_width 0.5)
				(island_removal_mode 0)
			)
			(polygon
				(pts
					(xy 278.91994 -407.549858) (xy 278.91994 -402.649944) (xy 286.949896 -402.649944) (xy 286.949896 -407.549858)
				)
			)
		)
	)
	(footprint ""
		(layer "F.Cu")
		(at 256.286 -233.045 90)
		(property "Reference" "Q17"
			(at 0 0 90)
			(layer "F.SilkS")
			(hide yes)
			(effects
				(font
					(size 1.27 1.27)
				)
			)
		)
		(property "Value" "SSM3K324R-GP"
			(at 0.127 -8.9662 90)
			(unlocked yes)
			(layer "F.Fab")
			(hide yes)
			(effects
				(font
					(size 1.016 1.016)
					(thickness 0.1524)
				)
			)
		)
		(property "Device Type" "SOT23DGS2D4H35"
			(at 0.127 -10.4902 90)
			(unlocked yes)
			(layer "F.Fab")
			(hide yes)
			(effects
				(font
					(size 1.016 1.016)
					(thickness 0.1524)
				)
			)
		)
		(duplicate_pad_numbers_are_jumpers no)
		(fp_line
			(start 1.651 -1.778)
			(end -1.651 -1.778)
			(stroke
				(width 0.1524)
				(type default)
			)
			(layer "F.SilkS")
		)
		(fp_line
			(start -1.651 -1.778)
			(end -1.651 1.778)
			(stroke
				(width 0.1524)
				(type default)
			)
			(layer "F.SilkS")
		)
		(fp_line
			(start 1.651 1.778)
			(end 1.651 -1.778)
			(stroke
				(width 0.1524)
				(type default)
			)
			(layer "F.SilkS")
		)
		(fp_line
			(start -1.651 1.778)
			(end 1.651 1.778)
			(stroke
				(width 0.1524)
				(type default)
			)
			(layer "F.SilkS")
		)
		(fp_poly
			(pts
				(xy -1.778 1.8796) (xy -1.778 -1.8796) (xy 1.778 -1.8796) (xy 1.778 1.8796)
			)
			(stroke
				(width 0)
				(type default)
			)
			(fill no)
			(layer "F.CrtYd")
		)
		(fp_poly
			(pts
				(xy -1.778 1.8796) (xy -1.778 -1.8796) (xy 1.778 -1.8796) (xy 1.778 1.8796)
			)
			(stroke
				(width 0)
				(type default)
			)
			(fill no)
			(layer "F.Fab")
		)
		(pad "D" smd custom
			(at 0 -0.9525 90)
			(size 0.1905 0.1905)
			(layers "F.Cu" "F.Mask" "F.Paste")
			(net "P3V3_STBY_A")
			(options
				(clearance outline)
				(anchor circle)
			)
			(primitives
				(gr_poly
					(pts
						(arc
							(start -0.1778 0.5715)
							(mid -0.321484 0.511984)
							(end -0.381 0.3683)
						)
						(arc
							(start -0.381 -0.3683)
							(mid -0.321484 -0.511984)
							(end -0.1778 -0.5715)
						)
						(arc
							(start 0.1778 -0.5715)
							(mid 0.321484 -0.511984)
							(end 0.381 -0.3683)
						)
						(arc
							(start 0.381 0.3683)
							(mid 0.321484 0.511984)
							(end 0.1778 0.5715)
						)
					)
					(width 0)
					(fill yes)
				)
			)
		)
		(pad "G" smd custom
			(at -0.98425 0.9525 90)
			(size 0.1905 0.1905)
			(layers "F.Cu" "F.Mask" "F.Paste")
			(net "SCC_FULL_PWR_EN_5V")
			(options
				(clearance outline)
				(anchor circle)
			)
			(primitives
				(gr_poly
					(pts
						(arc
							(start -0.1778 0.5715)
							(mid -0.321484 0.511984)
							(end -0.381 0.3683)
						)
						(arc
							(start -0.381 -0.3683)
							(mid -0.321484 -0.511984)
							(end -0.1778 -0.5715)
						)
						(arc
							(start 0.1778 -0.5715)
							(mid 0.321484 -0.511984)
							(end 0.381 -0.3683)
						)
						(arc
							(start 0.381 0.3683)
							(mid 0.321484 0.511984)
							(end 0.1778 0.5715)
						)
					)
					(width 0)
					(fill yes)
				)
			)
		)
		(pad "S" smd custom
			(at 0.98425 0.9525 90)
			(size 0.1905 0.1905)
			(layers "F.Cu" "F.Mask" "F.Paste")
			(net "GPIO_VCC_U9")
			(options
				(clearance outline)
				(anchor circle)
			)
			(primitives
				(gr_poly
					(pts
						(arc
							(start -0.1778 0.5715)
							(mid -0.321484 0.511984)
							(end -0.381 0.3683)
						)
						(arc
							(start -0.381 -0.3683)
							(mid -0.321484 -0.511984)
							(end -0.1778 -0.5715)
						)
						(arc
							(start 0.1778 -0.5715)
							(mid 0.321484 -0.511984)
							(end 0.381 -0.3683)
						)
						(arc
							(start 0.381 0.3683)
							(mid 0.321484 0.511984)
							(end 0.1778 0.5715)
						)
					)
					(width 0)
					(fill yes)
				)
			)
		)
	)
)
